(kicad_pcb
	(version 20260206)
	(generator "pcbnew")
	(generator_version "10.0")
	(general
		(thickness 1.6)
		(legacy_teardrops no)
	)
	(paper "A4")
	(title_block
		(title "03242023_DA0F0TMBIJ0_F0T_Motherboard_J_brd_V01_OCP.brd")
		(comment 1 "Grand Teton / footprint 1187 of 6105 (U249), pads 105-206 of 484")
	)
	(layers
		(0 "F.Cu" signal "TOP")
		(4 "In1.Cu" signal "GND")
		(6 "In2.Cu" signal "IN1")
		(8 "In3.Cu" signal "GND1")
		(10 "In4.Cu" signal "IN2")
		(12 "In5.Cu" signal "GND2")
		(14 "In6.Cu" signal "IN3")
		(16 "In7.Cu" signal "GND3")
		(18 "In8.Cu" signal "VCC")
		(20 "In9.Cu" signal "VCC1")
		(22 "In10.Cu" signal "GND4")
		(24 "In11.Cu" signal "IN4")
		(26 "In12.Cu" signal "GND5")
		(28 "In13.Cu" signal "IN5")
		(30 "In14.Cu" signal "GND6")
		(32 "In15.Cu" signal "IN6")
		(34 "In16.Cu" signal "GND7")
		(2 "B.Cu" signal "BOTTOM")
		(9 "F.Adhes" user "F.Adhesive")
		(11 "B.Adhes" user "B.Adhesive")
		(13 "F.Paste" user "Package Geometry/Pastemask Top")
		(15 "B.Paste" user "Package Geometry/Pastemask Bottom")
		(5 "F.SilkS" user "Ref Des/Silkscreen Top")
		(7 "B.SilkS" user "Ref Des/Silkscreen Bottom")
		(1 "F.Mask" user "Board Geometry/Soldermask Top")
		(3 "B.Mask" user "Board Geometry/Soldermask Bottom")
		(17 "Dwgs.User" user "User.Drawings")
		(19 "Cmts.User" user "User.Comments")
		(21 "Eco1.User" user "User.Eco1")
		(23 "Eco2.User" user "User.Eco2")
		(25 "Edge.Cuts" user "Board Geometry/Outline")
		(27 "Margin" user)
		(31 "F.CrtYd" user "Package Geometry/Place Bound Top")
		(29 "B.CrtYd" user "Package Geometry/Place Bound Bottom")
		(35 "F.Fab" user "Ref Des/Assembly Top")
		(33 "B.Fab" user "Ref Des/Assembly Bottom")
	)
	(footprint ""
		(layer "F.Cu")
		(at 178.55565 -113.37544 90)
		(property "Reference" "U249"
			(at -11.966194 -11.833098 0)
			(unlocked yes)
			(layer "F.SilkS")
			(effects
				(font
					(size 0.7874 0.5842)
					(thickness 0.1524)
				)
				(justify left)
			)
		)
		(property "Value" ""
			(at 0 0 90)
			(layer "F.Fab")
			(effects
				(font
					(size 1.27 1.27)
				)
			)
		)
		(duplicate_pad_numbers_are_jumpers no)
		(pad "C17" smd circle
			(at 4.400042 -6.800088 90)
			(size 0.4064 0.4064)
			(layers "F.Cu" "F.Mask" "F.Paste")
			(net "SGPIO_OCP_SFF_DATAIN")
		)
		(pad "C18" smd circle
			(at 5.199888 -6.800088 90)
			(size 0.4064 0.4064)
			(layers "F.Cu" "F.Mask" "F.Paste")
			(net "JTAG_BMC_SW_PLD_OE")
		)
		(pad "C19" smd circle
			(at 5.999988 -6.800088 90)
			(size 0.4064 0.4064)
			(layers "F.Cu" "F.Mask" "F.Paste")
			(net "NC_FPGA_PT43C")
		)
		(pad "C20" smd circle
			(at 6.800088 -6.800088 90)
			(size 0.4064 0.4064)
			(layers "F.Cu" "F.Mask" "F.Paste")
			(net "NC_FPGA_PT43D")
		)
		(pad "C21" smd circle
			(at 7.599934 -6.800088 90)
			(size 0.4064 0.4064)
			(layers "F.Cu" "F.Mask" "F.Paste")
			(net "FM_PVCCD_HV_CPU0_EN")
		)
		(pad "C22" smd circle
			(at 8.400034 -6.800088 90)
			(size 0.4064 0.4064)
			(layers "F.Cu" "F.Mask" "F.Paste")
			(net "FM_PVCCD_HV_CPU1_EN")
		)
		(pad "D1" smd circle
			(at -8.400034 -5.999988 90)
			(size 0.4064 0.4064)
			(layers "F.Cu" "F.Mask" "F.Paste")
			(net "RST_PLD_CPU1_DRAM_AB_N")
		)
		(pad "D2" smd circle
			(at -7.599934 -5.999988 90)
			(size 0.4064 0.4064)
			(layers "F.Cu" "F.Mask" "F.Paste")
			(net "RST_PLD_CPU0_DRAM_CD_N")
		)
		(pad "D3" smd circle
			(at -6.800088 -5.999988 90)
			(size 0.4064 0.4064)
			(layers "F.Cu" "F.Mask" "F.Paste")
			(net "RST_CPU0_DRAM_AB_PLD_LVT3_N")
		)
		(pad "D4" smd circle
			(at -5.999988 -5.999988 90)
			(size 0.4064 0.4064)
			(layers "F.Cu" "F.Mask" "F.Paste")
			(net "RST_CPU0_DRAM_CD_PLD_LVT3_N")
		)
		(pad "D5" smd circle
			(at -5.199888 -5.999988 90)
			(size 0.4064 0.4064)
			(layers "F.Cu" "F.Mask" "F.Paste")
			(net "VIRTUAL_RESEAT_FPGA_R_N")
		)
		(pad "D6" smd circle
			(at -4.400042 -5.999988 90)
			(size 0.4064 0.4064)
			(layers "F.Cu" "F.Mask" "F.Paste")
			(net "OCP_V3_2_AUX_PWR_PLD_EN")
		)
		(pad "D7" smd circle
			(at -3.599942 -5.999988 90)
			(size 0.4064 0.4064)
			(layers "F.Cu" "F.Mask" "F.Paste")
			(net "FM_S3M_CPU1_CPLD_CRC_ERROR")
		)
		(pad "D8" smd circle
			(at -2.800096 -5.999988 90)
			(size 0.4064 0.4064)
			(layers "F.Cu" "F.Mask" "F.Paste")
			(net "IRQ_SML1_PMBUS_BMC_ALERT_N")
		)
		(pad "D9" smd circle
			(at -1.999996 -5.999988 90)
			(size 0.4064 0.4064)
			(layers "F.Cu" "F.Mask" "F.Paste")
			(net "PU_RST_DEDI_BUSY_PLD_N")
		)
		(pad "D10" smd circle
			(at -1.199896 -5.999988 90)
			(size 0.4064 0.4064)
			(layers "F.Cu" "F.Mask" "F.Paste")
			(net "JTAG_PLD_TCK_R")
		)
		(pad "D11" smd circle
			(at -0.40005 -5.999988 90)
			(size 0.4064 0.4064)
			(layers "F.Cu" "F.Mask" "F.Paste")
			(net "GPU_FPGA_EROT_FATALERR_ISO_R_N")
		)
		(pad "D12" smd circle
			(at 0.40005 -5.999988 90)
			(size 0.4064 0.4064)
			(layers "F.Cu" "F.Mask" "F.Paste")
			(net "PWRGD_P5V_AUX_R2")
		)
		(pad "D13" smd circle
			(at 1.199896 -5.999988 90)
			(size 0.4064 0.4064)
			(layers "F.Cu" "F.Mask" "F.Paste")
			(net "PWRGD_PVPP_HBM_CPU0")
		)
		(pad "D14" smd circle
			(at 1.999996 -5.999988 90)
			(size 0.4064 0.4064)
			(layers "F.Cu" "F.Mask" "F.Paste")
			(net "SGPIO_BMC_CLK")
		)
		(pad "D15" smd circle
			(at 2.800096 -5.999988 90)
			(size 0.4064 0.4064)
			(layers "F.Cu" "F.Mask" "F.Paste")
			(net "SGPIO_DEBUG_PLD_LD_N")
		)
		(pad "D16" smd circle
			(at 3.599942 -5.999988 90)
			(size 0.4064 0.4064)
			(layers "F.Cu" "F.Mask" "F.Paste")
			(net "SGPIO_OCP_SFF_LD_N")
		)
		(pad "D17" smd circle
			(at 4.400042 -5.999988 90)
			(size 0.4064 0.4064)
			(layers "F.Cu" "F.Mask" "F.Paste")
			(net "SGPIO_OCP_V3_2_LD_N")
		)
		(pad "D18" smd circle
			(at 5.199888 -5.999988 90)
			(size 0.4064 0.4064)
			(layers "F.Cu" "F.Mask" "F.Paste")
			(net "NC_FPGA_PT41D")
		)
		(pad "D19" smd circle
			(at 5.999988 -5.999988 90)
			(size 0.4064 0.4064)
			(layers "F.Cu" "F.Mask" "F.Paste")
			(net "FM_PVCCINFAON_CPU0_R_EN")
		)
		(pad "D20" smd circle
			(at 6.800088 -5.999988 90)
			(size 0.4064 0.4064)
			(layers "F.Cu" "F.Mask" "F.Paste")
			(net "FM_PVCCINFAON_CPU1_R_EN")
		)
		(pad "D21" smd circle
			(at 7.599934 -5.999988 90)
			(size 0.4064 0.4064)
			(layers "F.Cu" "F.Mask" "F.Paste")
			(net "FM_PVCCFA_EHV_FIVRA_CPU1_R_EN")
		)
		(pad "D22" smd circle
			(at 8.400034 -5.999988 90)
			(size 0.4064 0.4064)
			(layers "F.Cu" "F.Mask" "F.Paste")
			(net "FM_PVCCFA_EHV_FIVRA_CPU0_R_EN")
		)
		(pad "E1" smd circle
			(at -8.400034 -5.199888 90)
			(size 0.4064 0.4064)
			(layers "F.Cu" "F.Mask" "F.Paste")
			(net "Net_1460")
		)
		(pad "E2" smd circle
			(at -7.599934 -5.199888 90)
			(size 0.4064 0.4064)
			(layers "F.Cu" "F.Mask" "F.Paste")
			(net "RST_PLD_CPU1_DRAM_CD_N")
		)
		(pad "E3" smd circle
			(at -6.800088 -5.199888 90)
			(size 0.4064 0.4064)
			(layers "F.Cu" "F.Mask" "F.Paste")
			(net "RST_PLD_CPU1_DRAM_EF_N")
		)
		(pad "E4" smd circle
			(at -5.999988 -5.199888 90)
			(size 0.4064 0.4064)
			(layers "F.Cu" "F.Mask" "F.Paste")
			(net "RST_CPU1_DRAM_AB_PLD_LVT3_N")
		)
		(pad "E5" smd circle
			(at -5.199888 -5.199888 90)
			(size 0.4064 0.4064)
			(layers "F.Cu" "F.Mask" "F.Paste")
			(net "GND")
		)
		(pad "E6" smd circle
			(at -4.400042 -5.199888 90)
			(size 0.4064 0.4064)
			(layers "F.Cu" "F.Mask" "F.Paste")
			(net "FM_SWB_PWRGD_ISO_R")
		)
		(pad "E7" smd circle
			(at -3.599942 -5.199888 90)
			(size 0.4064 0.4064)
			(layers "F.Cu" "F.Mask" "F.Paste")
			(net "OCP_SFF_AUX_PWR_PLD_EN")
		)
		(pad "E8" smd circle
			(at -2.800096 -5.199888 90)
			(size 0.4064 0.4064)
			(layers "F.Cu" "F.Mask" "F.Paste")
			(net "JTAG_PLD_TDO_R")
		)
		(pad "E9" smd circle
			(at -1.999996 -5.199888 90)
			(size 0.4064 0.4064)
			(layers "F.Cu" "F.Mask" "F.Paste")
			(net "JTAG_PLD_TDI_R")
		)
		(pad "E10" smd circle
			(at -1.199896 -5.199888 90)
			(size 0.4064 0.4064)
			(layers "F.Cu" "F.Mask" "F.Paste")
			(net "GPU_HMC_PRSNT_ISO_R_N")
		)
		(pad "E11" smd circle
			(at -0.40005 -5.199888 90)
			(size 0.4064 0.4064)
			(layers "F.Cu" "F.Mask" "F.Paste")
			(net "GPU_PRSNT_N_ISO_R")
		)
		(pad "E12" smd circle
			(at 0.40005 -5.199888 90)
			(size 0.4064 0.4064)
			(layers "F.Cu" "F.Mask" "F.Paste")
			(net "PWRGD_P3V3")
		)
		(pad "E13" smd circle
			(at 1.199896 -5.199888 90)
			(size 0.4064 0.4064)
			(layers "F.Cu" "F.Mask" "F.Paste")
			(net "PWRGD_PVCCFA_EHV_FIVRA_CPU0")
		)
		(pad "E14" smd circle
			(at 1.999996 -5.199888 90)
			(size 0.4064 0.4064)
			(layers "F.Cu" "F.Mask" "F.Paste")
			(net "JTAG_PLD_JTAGEN")
		)
		(pad "E15" smd circle
			(at 2.800096 -5.199888 90)
			(size 0.4064 0.4064)
			(layers "F.Cu" "F.Mask" "F.Paste")
			(net "PU_FPGA_D12_PROGRAMN")
		)
		(pad "E16" smd circle
			(at 3.599942 -5.199888 90)
			(size 0.4064 0.4064)
			(layers "F.Cu" "F.Mask" "F.Paste")
			(net "SGPIO_OCP_V3_2_DATAIN")
		)
		(pad "E17" smd circle
			(at 4.400042 -5.199888 90)
			(size 0.4064 0.4064)
			(layers "F.Cu" "F.Mask" "F.Paste")
			(net "NC_FPGA_PT44D")
		)
		(pad "E18" smd circle
			(at 5.199888 -5.199888 90)
			(size 0.4064 0.4064)
			(layers "F.Cu" "F.Mask" "F.Paste")
			(net "GND")
		)
		(pad "E19" smd circle
			(at 5.999988 -5.199888 90)
			(size 0.4064 0.4064)
			(layers "F.Cu" "F.Mask" "F.Paste")
			(net "FM_PVCCIN_CPU0_R_EN")
		)
		(pad "E20" smd circle
			(at 6.800088 -5.199888 90)
			(size 0.4064 0.4064)
			(layers "F.Cu" "F.Mask" "F.Paste")
			(net "FM_PVCCIN_CPU1_R_EN")
		)
		(pad "E21" smd circle
			(at 7.599934 -5.199888 90)
			(size 0.4064 0.4064)
			(layers "F.Cu" "F.Mask" "F.Paste")
			(net "FM_PVNN_MAIN_CPU1_EN")
		)
		(pad "E22" smd circle
			(at 8.400034 -5.199888 90)
			(size 0.4064 0.4064)
			(layers "F.Cu" "F.Mask" "F.Paste")
			(net "FM_PVNN_MAIN_CPU0_EN")
		)
		(pad "F1" smd circle
			(at -8.400034 -4.400042 90)
			(size 0.4064 0.4064)
			(layers "F.Cu" "F.Mask" "F.Paste")
			(net "Net_1461")
		)
		(pad "F2" smd circle
			(at -7.599934 -4.400042 90)
			(size 0.4064 0.4064)
			(layers "F.Cu" "F.Mask" "F.Paste")
			(net "GND")
		)
		(pad "F3" smd circle
			(at -6.800088 -4.400042 90)
			(size 0.4064 0.4064)
			(layers "F.Cu" "F.Mask" "F.Paste")
			(net "P3V3_AUX_FPGA_VCCIO5")
		)
		(pad "F4" smd circle
			(at -5.999988 -4.400042 90)
			(size 0.4064 0.4064)
			(layers "F.Cu" "F.Mask" "F.Paste")
			(net "RST_PLD_CPU1_DRAM_GH_N")
		)
		(pad "F5" smd circle
			(at -5.199888 -4.400042 90)
			(size 0.4064 0.4064)
			(layers "F.Cu" "F.Mask" "F.Paste")
			(net "RST_CPU1_DRAM_CD_PLD_LVT3_N")
		)
		(pad "F6" smd circle
			(at -4.400042 -4.400042 90)
			(size 0.4064 0.4064)
			(layers "F.Cu" "F.Mask" "F.Paste")
			(net "RST_CPU0_DRAM_EF_PLD_LVT3_N")
		)
		(pad "F7" smd circle
			(at -3.599942 -4.400042 90)
			(size 0.4064 0.4064)
			(layers "F.Cu" "F.Mask" "F.Paste")
			(net "FM_GPU_PWRGD_ISO_R")
		)
		(pad "F8" smd circle
			(at -2.800096 -4.400042 90)
			(size 0.4064 0.4064)
			(layers "F.Cu" "F.Mask" "F.Paste")
			(net "RST_BMC_FROM_SWB_ISO_R_N")
		)
		(pad "F9" smd circle
			(at -1.999996 -4.400042 90)
			(size 0.4064 0.4064)
			(layers "F.Cu" "F.Mask" "F.Paste")
			(net "GPU_FPGA_EROT_RST_R_N")
		)
		(pad "F10" smd circle
			(at -1.199896 -4.400042 90)
			(size 0.4064 0.4064)
			(layers "F.Cu" "F.Mask" "F.Paste")
			(net "GPU_BASE_HMC_READY_ISO_R")
		)
		(pad "F11" smd circle
			(at -0.40005 -4.400042 90)
			(size 0.4064 0.4064)
			(layers "F.Cu" "F.Mask" "F.Paste")
			(net "GPU_FPGA_EROT_RECOV_R_N")
		)
		(pad "F12" smd circle
			(at 0.40005 -4.400042 90)
			(size 0.4064 0.4064)
			(layers "F.Cu" "F.Mask" "F.Paste")
			(net "PWRGD_PVCCD_HV_CPU0")
		)
		(pad "F13" smd circle
			(at 1.199896 -4.400042 90)
			(size 0.4064 0.4064)
			(layers "F.Cu" "F.Mask" "F.Paste")
			(net "PWRGD_PVCCIN_CPU0")
		)
		(pad "F14" smd circle
			(at 1.999996 -4.400042 90)
			(size 0.4064 0.4064)
			(layers "F.Cu" "F.Mask" "F.Paste")
			(net "SGPIO_BMC_LD_N")
		)
		(pad "F15" smd circle
			(at 2.800096 -4.400042 90)
			(size 0.4064 0.4064)
			(layers "F.Cu" "F.Mask" "F.Paste")
			(net "RST_SRST_PLD_BMC_R_N")
		)
		(pad "F16" smd circle
			(at 3.599942 -4.400042 90)
			(size 0.4064 0.4064)
			(layers "F.Cu" "F.Mask" "F.Paste")
			(net "NC_FPGA_PT44C")
		)
		(pad "F17" smd circle
			(at 4.400042 -4.400042 90)
			(size 0.4064 0.4064)
			(layers "F.Cu" "F.Mask" "F.Paste")
			(net "FM_PVCCFA_EHV_CPU0_R_EN")
		)
		(pad "F18" smd circle
			(at 5.199888 -4.400042 90)
			(size 0.4064 0.4064)
			(layers "F.Cu" "F.Mask" "F.Paste")
			(net "FM_AUX_SW_EN")
		)
		(pad "F19" smd circle
			(at 5.999988 -4.400042 90)
			(size 0.4064 0.4064)
			(layers "F.Cu" "F.Mask" "F.Paste")
			(net "FM_PCH_P1V8_AUX_EN")
		)
		(pad "F20" smd circle
			(at 6.800088 -4.400042 90)
			(size 0.4064 0.4064)
			(layers "F.Cu" "F.Mask" "F.Paste")
			(net "P3V3_AUX_FPGA_VCCIO1")
		)
		(pad "F21" smd circle
			(at 7.599934 -4.400042 90)
			(size 0.4064 0.4064)
			(layers "F.Cu" "F.Mask" "F.Paste")
			(net "GND")
		)
		(pad "F22" smd circle
			(at 8.400034 -4.400042 90)
			(size 0.4064 0.4064)
			(layers "F.Cu" "F.Mask" "F.Paste")
			(net "FM_PVPP_HBM_CPU1_EN")
		)
		(pad "G1" smd circle
			(at -8.400034 -3.599942 90)
			(size 0.4064 0.4064)
			(layers "F.Cu" "F.Mask" "F.Paste")
			(net "PWRGD_DRAMPWRGD_CPU0_CD_R_LVC1")
		)
		(pad "G2" smd circle
			(at -7.599934 -3.599942 90)
			(size 0.4064 0.4064)
			(layers "F.Cu" "F.Mask" "F.Paste")
			(net "PWRGD_DRAMPWRGD_CPU0_AB_R_LVC1")
		)
		(pad "G3" smd circle
			(at -6.800088 -3.599942 90)
			(size 0.4064 0.4064)
			(layers "F.Cu" "F.Mask" "F.Paste")
			(net "Net_1462")
		)
		(pad "G4" smd circle
			(at -5.999988 -3.599942 90)
			(size 0.4064 0.4064)
			(layers "F.Cu" "F.Mask" "F.Paste")
			(net "Net_1463")
		)
		(pad "G5" smd circle
			(at -5.199888 -3.599942 90)
			(size 0.4064 0.4064)
			(layers "F.Cu" "F.Mask" "F.Paste")
			(net "RST_PLD_CPU0_DRAM_EF_N")
		)
		(pad "G6" smd circle
			(at -4.400042 -3.599942 90)
			(size 0.4064 0.4064)
			(layers "F.Cu" "F.Mask" "F.Paste")
			(net "RST_CPU1_DRAM_EF_PLD_LVT3_N")
		)
		(pad "G7" smd circle
			(at -3.599942 -3.599942 90)
			(size 0.4064 0.4064)
			(layers "F.Cu" "F.Mask" "F.Paste")
			(net "RST_CPU0_DRAM_GH_PLD_LVT3_N")
		)
		(pad "G8" smd circle
			(at -2.800096 -3.599942 90)
			(size 0.4064 0.4064)
			(layers "F.Cu" "F.Mask" "F.Paste")
			(net "SMB_BMC_GPU_EN")
		)
		(pad "G9" smd circle
			(at -1.999996 -3.599942 90)
			(size 0.4064 0.4064)
			(layers "F.Cu" "F.Mask" "F.Paste")
			(net "GPU_BASE_STBY_EN_R")
		)
		(pad "G10" smd circle
			(at -1.199896 -3.599942 90)
			(size 0.4064 0.4064)
			(layers "F.Cu" "F.Mask" "F.Paste")
			(net "P3V3_AUX_FPGA_VCCIO0")
		)
		(pad "G11" smd circle
			(at -0.40005 -3.599942 90)
			(size 0.4064 0.4064)
			(layers "F.Cu" "F.Mask" "F.Paste")
			(net "GPU_FPGA_BOOT_EN_R")
		)
		(pad "G12" smd circle
			(at 0.40005 -3.599942 90)
			(size 0.4064 0.4064)
			(layers "F.Cu" "F.Mask" "F.Paste")
			(net "PWRGD_P3V3_AUX_PLD")
		)
		(pad "G13" smd circle
			(at 1.199896 -3.599942 90)
			(size 0.4064 0.4064)
			(layers "F.Cu" "F.Mask" "F.Paste")
			(net "P3V3_AUX_FPGA_VCCIO0")
		)
		(pad "G14" smd circle
			(at 1.999996 -3.599942 90)
			(size 0.4064 0.4064)
			(layers "F.Cu" "F.Mask" "F.Paste")
			(net "SGPIO_BMC_DIN_R")
		)
		(pad "G15" smd circle
			(at 2.800096 -3.599942 90)
			(size 0.4064 0.4064)
			(layers "F.Cu" "F.Mask" "F.Paste")
			(net "NC_FPGA_PT42D")
		)
		(pad "G16" smd circle
			(at 3.599942 -3.599942 90)
			(size 0.4064 0.4064)
			(layers "F.Cu" "F.Mask" "F.Paste")
			(net "FM_PVCCFA_EHV_CPU1_R_EN")
		)
		(pad "G17" smd circle
			(at 4.400042 -3.599942 90)
			(size 0.4064 0.4064)
			(layers "F.Cu" "F.Mask" "F.Paste")
			(net "PWRGD_PVCCINFAON_CPU0")
		)
		(pad "G18" smd circle
			(at 5.199888 -3.599942 90)
			(size 0.4064 0.4064)
			(layers "F.Cu" "F.Mask" "F.Paste")
			(net "PWRGD_PVCCIN_CPU1")
		)
		(pad "G19" smd circle
			(at 5.999988 -3.599942 90)
			(size 0.4064 0.4064)
			(layers "F.Cu" "F.Mask" "F.Paste")
			(net "FM_ESPI_PLD_R_EN")
		)
		(pad "G20" smd circle
			(at 6.800088 -3.599942 90)
			(size 0.4064 0.4064)
			(layers "F.Cu" "F.Mask" "F.Paste")
			(net "FM_P1V05_PCH_AUX_EN")
		)
		(pad "G21" smd circle
			(at 7.599934 -3.599942 90)
			(size 0.4064 0.4064)
			(layers "F.Cu" "F.Mask" "F.Paste")
			(net "FM_P5V_EN")
		)
		(pad "G22" smd circle
			(at 8.400034 -3.599942 90)
			(size 0.4064 0.4064)
			(layers "F.Cu" "F.Mask" "F.Paste")
			(net "FM_PVPP_HBM_CPU0_EN")
		)
		(pad "H1" smd circle
			(at -8.400034 -2.800096 90)
			(size 0.4064 0.4064)
			(layers "F.Cu" "F.Mask" "F.Paste")
			(net "PWRGD_DRAMPWRGD_CPU1_CD_R_LVC1")
		)
		(pad "H2" smd circle
			(at -7.599934 -2.800096 90)
			(size 0.4064 0.4064)
			(layers "F.Cu" "F.Mask" "F.Paste")
			(net "PWRGD_DRAMPWRGD_CPU1_AB_R_LVC1")
		)
		(pad "H3" smd circle
			(at -6.800088 -2.800096 90)
			(size 0.4064 0.4064)
			(layers "F.Cu" "F.Mask" "F.Paste")
			(net "PWRGD_DRAMPWRGD_CPU0_GH_R_LVC1")
		)
		(pad "H4" smd circle
			(at -5.999988 -2.800096 90)
			(size 0.4064 0.4064)
			(layers "F.Cu" "F.Mask" "F.Paste")
			(net "PWRGD_DRAMPWRGD_CPU0_EF_R_LVC1")
		)
		(pad "H5" smd circle
			(at -5.199888 -2.800096 90)
			(size 0.4064 0.4064)
			(layers "F.Cu" "F.Mask" "F.Paste")
			(net "FM_BOARD_BMC_SKU_ID4")
		)
		(pad "H6" smd circle
			(at -4.400042 -2.800096 90)
			(size 0.4064 0.4064)
			(layers "F.Cu" "F.Mask" "F.Paste")
			(net "RST_PLD_CPU0_DRAM_GH_N")
		)
		(pad "H7" smd circle
			(at -3.599942 -2.800096 90)
			(size 0.4064 0.4064)
			(layers "F.Cu" "F.Mask" "F.Paste")
			(net "RST_CPU1_DRAM_GH_PLD_LVT3_N")
		)
		(pad "H8" smd circle
			(at -2.800096 -2.800096 90)
			(size 0.4064 0.4064)
			(layers "F.Cu" "F.Mask" "F.Paste")
			(net "GND")
		)
	)
)
